# T6G (Grand Teton) — schematic netlist excerpt (pin names and nets, part order shuffled) for the footprints in the layout excerpt that follows; sources: Cadence DE-HDL packaged netlist, KiCad conversion of 04192023_DAF0TMB3IC0_F0TG_MB_C_brd_V02_OCP.brd

J16  SCONN288_DDR506112002KQ  IO  pkg DDR288S_1-1VXC  page 92
  VIN_BULK0  = P12V_MEM_CPU0
  RFU0  = NC
  VIN_MGMT  = P3V3_AUX
  HSCL  = I3C_SPD_DDRG_CPU0_SCL
  HSDA  = I3C_SPD_DDRG_CPU0_SDA
  VSS0  = GND
  DQ0_A  = M_G_CPU0_SA_DQ<0>
  VSS1  = GND
  DQ1_A  = M_G_CPU0_SA_DQ<1>
  VSS2  = GND
  DQS0_A_T  = M_G_CPU0_SA_DQS_DP<0>
  DQS0_A_C  = M_G_CPU0_SA_DQS_DN<0>
  VSS3  = GND
  DQ4_A  = M_G_CPU0_SA_DQ<4>
  VSS4  = GND
  DQ5_A  = M_G_CPU0_SA_DQ<5>
  VSS5  = GND
  DQ8_A  = M_G_CPU0_SA_DQ<8>
  VSS6  = GND
  DQ9_A  = M_G_CPU0_SA_DQ<9>
  VSS7  = GND
  DQS1_A_T  = M_G_CPU0_SA_DQS_DP<1>
  DQS1_A_C  = M_G_CPU0_SA_DQS_DN<1>
  VSS8  = GND
  DQ12_A  = M_G_CPU0_SA_DQ<12>
  VSS9  = GND
  DQ13_A  = M_G_CPU0_SA_DQ<13>
  VSS10  = GND
  DQ16_A  = M_G_CPU0_SA_DQ<16>
  VSS11  = GND
  DQ17_A  = M_G_CPU0_SA_DQ<17>
  VSS12  = GND
  DQS2_A_T  = M_G_CPU0_SA_DQS_DP<2>
  DQS2_A_C  = M_G_CPU0_SA_DQS_DN<2>
  VSS13  = GND
  DQ20_A  = M_G_CPU0_SA_DQ<20>
  VSS14  = GND
  DQ21_A  = M_G_CPU0_SA_DQ<21>
  VSS15  = GND
  DQ24_A  = M_G_CPU0_SA_DQ<24>
  VSS16  = GND
  DQ25_A  = M_G_CPU0_SA_DQ<25>
  VSS17  = GND
  DQS3_A_T  = M_G_CPU0_SA_DQS_DP<3>
  DQS3_A_C  = M_G_CPU0_SA_DQS_DN<3>
  VSS18  = GND
  DQ28_A  = M_G_CPU0_SA_DQ<28>
  VSS19  = GND
  DQ29_A  = M_G_CPU0_SA_DQ<29>
  VSS20  = GND
  CB0_A  = M_G_CPU0_SA_CB<0>
  VSS21  = GND
  CB1_A  = M_G_CPU0_SA_CB<1>
  VSS22  = GND
  DQS4_A_T  = M_G_CPU0_SA_DQS_DP<4>
  DQS4_A_C  = M_G_CPU0_SA_DQS_DN<4>
  VSS23  = GND
  CB4_A  = M_G_CPU0_SA_CB<4>
  VSS24  = GND
  CB5_A  = M_G_CPU0_SA_CB<5>
  VSS25  = GND
  ALERT_N  = M_G_CPU0_ALERT_N
  VSS26  = GND
  CS0_A_N  = M_G_CPU0_SA_CS_N<0>
  VSS27  = GND
  CA0_A  = M_G_CPU0_SA_CA<0>
  VSS28  = GND
  CA2_A  = M_G_CPU0_SA_CA<2>
  VSS29  = GND
  CA4_A  = M_G_CPU0_SA_CA<4>
  VSS30  = GND
  CA6_A  = M_G_CPU0_SA_CA<6>
  VSS31  = GND
  PAR_A  = M_G_CPU0_SA_PAR
  VSS32  = GND
  CA0_B  = M_G_CPU0_SB_CA<0>
  VSS33  = GND
  CA2_B  = M_G_CPU0_SB_CA<2>
  VSS34  = GND
  CA4_B  = M_G_CPU0_SB_CA<4>
  VSS35  = GND
  CA6_B  = M_G_CPU0_SB_CA<6>
  VSS36  = GND
  CS0_B_N  = M_G_CPU0_SB_CS_N<0>
  VSS37  = GND
  \lbd||rsp_a_n\  = M_G_CPU0_SA_RSP<0>
  \lbs||rsp_b_n\  = M_G_CPU0_SB_RSP<0>
  VSS38  = GND
  CB4_B  = M_G_CPU0_SB_CB<4>
  VSS39  = GND
  CB5_B  = M_G_CPU0_SB_CB<5>
  VSS40  = GND
  \dqs9_b_t||tdqs9_b_t||dbi4_b_n\  = M_G_CPU0_SB_DQS_DP<9>
  \dqs9_b_c||tdqs9_b_c\  = M_G_CPU0_SB_DQS_DN<9>
  VSS41  = GND
  CB0_B  = M_G_CPU0_SB_CB<0>
  VSS42  = GND
  CB1_B  = M_G_CPU0_SB_CB<1>
  VSS43  = GND
  DQ0_B  = M_G_CPU0_SB_DQ<0>
  VSS44  = GND
  DQ1_B  = M_G_CPU0_SB_DQ<1>
  VSS45  = GND
  DQS0_B_T  = M_G_CPU0_SB_DQS_DP<0>
  DQS0_B_C  = M_G_CPU0_SB_DQS_DN<0>
  VSS46  = GND
  DQ4_B  = M_G_CPU0_SB_DQ<4>
  VSS47  = GND
  DQ5_B  = M_G_CPU0_SB_DQ<5>
  VSS48  = GND
  DQ8_B  = M_G_CPU0_SB_DQ<8>
  VSS49  = GND
  DQ9_B  = M_G_CPU0_SB_DQ<9>
  VSS50  = GND
  DQS1_B_T  = M_G_CPU0_SB_DQS_DP<1>
  DQS1_B_C  = M_G_CPU0_SB_DQS_DN<1>
  VSS51  = GND
  DQ12_B  = M_G_CPU0_SB_DQ<12>
  VSS52  = GND
  DQ13_B  = M_G_CPU0_SB_DQ<13>
  VSS53  = GND
  DQ16_B  = M_G_CPU0_SB_DQ<16>
  VSS54  = GND
  DQ17_B  = M_G_CPU0_SB_DQ<17>
  VSS55  = GND
  DQS2_B_T  = M_G_CPU0_SB_DQS_DP<2>
  DQS2_B_C  = M_G_CPU0_SB_DQS_DN<2>
  VSS56  = GND
  DQ20_B  = M_G_CPU0_SB_DQ<20>
  VSS57  = GND
  DQ21_B  = M_G_CPU0_SB_DQ<21>
  VSS58  = GND
  DQ24_B  = M_G_CPU0_SB_DQ<24>
  VSS59  = GND
  DQ25_B  = M_G_CPU0_SB_DQ<25>
  VSS60  = GND
  DQS3_B_T  = M_G_CPU0_SB_DQS_DP<3>
  DQS3_B_C  = M_G_CPU0_SB_DQS_DN<3>
  VSS61  = GND
  DQ28_B  = M_G_CPU0_SB_DQ<28>
  VSS62  = GND
  DQ29_B  = M_G_CPU0_SB_DQ<29>
  VSS63  = GND
  RFU1  = NC
  VIN_BULK1  = P12V_MEM_CPU0
  VIN_BULK2  = P12V_MEM_CPU0
  \pwr_good||fail_n\  = PWRGD_CHG_CPU0_DIMM0
  HAS  = PD_CHG_CPU0_DIMM0_SAA
  RFU2  = NC
  RFU3  = NC
  VSS64  = GND
  DQ2_A  = M_G_CPU0_SA_DQ<2>
  VSS65  = GND
  DQ3_A  = M_G_CPU0_SA_DQ<3>
  VSS66  = GND
  \dqs5_a_c||tdqs5_a_c||dqs5_a_t||tdqs5_a_t\  = M_G_CPU0_SA_DQS_DN<5>
  \dqs5_a_t||tdqs5_a_t\  = M_G_CPU0_SA_DQS_DP<5>
  VSS67  = GND
  DQ6_A  = M_G_CPU0_SA_DQ<6>
  VSS68  = GND
  DQ7_A  = M_G_CPU0_SA_DQ<7>
  VSS69  = GND
  DQ10_A  = M_G_CPU0_SA_DQ<10>
  VSS70  = GND
  DQ11_A  = M_G_CPU0_SA_DQ<11>
  VSS71  = GND
  \dqs6_a_c||tdqs6_a_c||dqs6_a_t||tdqs6_a_t\  = M_G_CPU0_SA_DQS_DN<6>
  \dqs6_a_t||tdqs6_a_t\  = M_G_CPU0_SA_DQS_DP<6>
  VSS72  = GND
  DQ14_A  = M_G_CPU0_SA_DQ<14>
  VSS73  = GND
  DQ15_A  = M_G_CPU0_SA_DQ<15>
  VSS74  = GND
  DQ18_A  = M_G_CPU0_SA_DQ<18>
  VSS75  = GND
  DQ19_A  = M_G_CPU0_SA_DQ<19>
  VSS76  = GND
  \dqs7_a_c||tdqs7_a_c\  = M_G_CPU0_SA_DQS_DN<7>
  \dqs7_a_t||tdqs7_a_t\  = M_G_CPU0_SA_DQS_DP<7>
  VSS77  = GND
  DQ22_A  = M_G_CPU0_SA_DQ<22>
  VSS78  = GND
  DQ23_A  = M_G_CPU0_SA_DQ<23>
  VSS79  = GND
  DQ26_A  = M_G_CPU0_SA_DQ<26>
  VSS80  = GND
  DQ27_A  = M_G_CPU0_SA_DQ<27>
  VSS81  = GND
  \dqs8_a_c||tdqs8_a_c\  = M_G_CPU0_SA_DQS_DN<8>
  \dqs8_a_t||tdqs8_a_t\  = M_G_CPU0_SA_DQS_DP<8>
  VSS82  = GND
  DQ30_A  = M_G_CPU0_SA_DQ<30>
  VSS83  = GND
  DQ31_A  = M_G_CPU0_SA_DQ<31>
  VSS84  = GND
  CB2_A  = M_G_CPU0_SA_CB<2>
  VSS85  = GND
  CB3_A  = M_G_CPU0_SA_CB<3>
  VSS86  = GND
  \dqs9_a_c||tdqs9_a_c\  = M_G_CPU0_SA_DQS_DN<9>
  \dqs9_a_t||tdqs9_a_t\  = M_G_CPU0_SA_DQS_DP<9>
  VSS87  = GND
  CB6_A  = M_G_CPU0_SA_CB<6>
  VSS88  = GND
  CB7_A  = M_G_CPU0_SA_CB<7>
  VSS89  = GND
  RESET_N  = M_G_CPU0_RESET_N
  VSS90  = GND
  CS1_A_N  = M_G_CPU0_SA_CS_N<1>
  VSS91  = GND
  CA1_A  = M_G_CPU0_SA_CA<1>
  VSS92  = GND
  CA3_A  = M_G_CPU0_SA_CA<3>
  VSS93  = GND
  CA5_A  = M_G_CPU0_SA_CA<5>
  VSS94  = GND
  CK_T  = M_G_CPU0_CLK_DP<0>
  CK_C  = M_G_CPU0_CLK_DN<0>
  VSS95  = GND
  RFU4  = NC
  CA1_B  = M_G_CPU0_SB_CA<1>
  VSS96  = GND
  CA3_B  = M_G_CPU0_SB_CA<3>
  VSS97  = GND
  CA5_B  = M_G_CPU0_SB_CA<5>
  VSS98  = GND
  PAR_B  = M_G_CPU0_SB_PAR
  VSS99  = GND
  CS1_B_N  = M_G_CPU0_SB_CS_N<1>
  VSS100  = GND
  RFU5  = NC
  RFU6  = NC
  VSS101  = GND
  CB6_B  = M_G_CPU0_SB_CB<6>
  VSS102  = GND
  CB7_B  = M_G_CPU0_SB_CB<7>
  VSS103  = GND
  DQS4_B_C  = M_G_CPU0_SB_DQS_DN<4>
  DQS4_B_T  = M_G_CPU0_SB_DQS_DP<4>
  VSS104  = GND
  CB2_B  = M_G_CPU0_SB_CB<2>
  VSS105  = GND
  CB3_B  = M_G_CPU0_SB_CB<3>
  VSS106  = GND
  DQ2_B  = M_G_CPU0_SB_DQ<2>
  VSS107  = GND
  DQ3_B  = M_G_CPU0_SB_DQ<3>
  VSS108  = GND
  \dqs5_b_c||tdqs5_b_c\  = M_G_CPU0_SB_DQS_DN<5>
  \dqs5_b_t||tdqs5_b_t\  = M_G_CPU0_SB_DQS_DP<5>
  VSS109  = GND
  DQ6_B  = M_G_CPU0_SB_DQ<6>
  VSS110  = GND
  DQ7_B  = M_G_CPU0_SB_DQ<7>
  VSS111  = GND
  DQ10_B  = M_G_CPU0_SB_DQ<10>
  VSS112  = GND
  DQ11_B  = M_G_CPU0_SB_DQ<11>
  VSS113  = GND
  \dqs6_b_c||tdqs6_b_c\  = M_G_CPU0_SB_DQS_DN<6>
  \dqs6_b_t||tdqs6_b_t\  = M_G_CPU0_SB_DQS_DP<6>
  VSS114  = GND
  DQ14_B  = M_G_CPU0_SB_DQ<14>
  VSS115  = GND
  DQ15_B  = M_G_CPU0_SB_DQ<15>
  VSS116  = GND
  DQ18_B  = M_G_CPU0_SB_DQ<18>
  VSS117  = GND
  DQ19_B  = M_G_CPU0_SB_DQ<19>
  VSS118  = GND
  \dqs7_b_c||tdqs7_b_c\  = M_G_CPU0_SB_DQS_DN<7>
  \dqs7_b_t||tdqs7_b_t\  = M_G_CPU0_SB_DQS_DP<7>
  VSS119  = GND
  DQ22_B  = M_G_CPU0_SB_DQ<22>
  VSS120  = GND
  DQ23_B  = M_G_CPU0_SB_DQ<23>
  VSS121  = GND
  DQ26_B  = M_G_CPU0_SB_DQ<26>
  VSS122  = GND
  DQ27_B  = M_G_CPU0_SB_DQ<27>
  VSS123  = GND
  \dqs8_b_c||tdqs8_b_c\  = M_G_CPU0_SB_DQS_DN<8>
  \dqs8_b_t||tdqs8_b_t\  = M_G_CPU0_SB_DQS_DP<8>
  VSS124  = GND
  DQ30_B  = M_G_CPU0_SB_DQ<30>
  VSS125  = GND
  DQ31_B  = M_G_CPU0_SB_DQ<31>
  VSS126  = GND
  G1  = GND
  G2  = GND
  G3  = GND

(kicad_pcb
	(version 20260206)
	(generator "pcbnew")
	(generator_version "10.0")
	(general
		(thickness 1.6)
		(legacy_teardrops no)
	)
	(paper "A4")
	(title_block
		(title "04192023_DAF0TMB3IC0_F0TG_MB_C_brd_V02_OCP.brd")
		(comment 1 "Grand Teton / footprint 1808 of 8354 (J16), pads 1-46 of 291")
	)
	(layers
		(0 "F.Cu" signal "TOP")
		(4 "In1.Cu" signal "GND")
		(6 "In2.Cu" signal "IN1")
		(8 "In3.Cu" signal "GND1")
		(10 "In4.Cu" signal "IN2")
		(12 "In5.Cu" signal "GND2")
		(14 "In6.Cu" signal "IN3")
		(16 "In7.Cu" signal "GND3")
		(18 "In8.Cu" signal "VCC")
		(20 "In9.Cu" signal "VCC1")
		(22 "In10.Cu" signal "GND4")
		(24 "In11.Cu" signal "IN4")
		(26 "In12.Cu" signal "GND5")
		(28 "In13.Cu" signal "IN5")
		(30 "In14.Cu" signal "GND6")
		(32 "In15.Cu" signal "IN6")
		(34 "In16.Cu" signal "GND7")
		(2 "B.Cu" signal "BOTTOM")
		(9 "F.Adhes" user "F.Adhesive")
		(11 "B.Adhes" user "B.Adhesive")
		(13 "F.Paste" user "Package Geometry/Pastemask Top")
		(15 "B.Paste" user "Package Geometry/Pastemask Bottom")
		(5 "F.SilkS" user "Ref Des/Silkscreen Top")
		(7 "B.SilkS" user "Ref Des/Silkscreen Bottom")
		(1 "F.Mask" user "Board Geometry/Soldermask Top")
		(3 "B.Mask" user "Board Geometry/Soldermask Bottom")
		(17 "Dwgs.User" user "User.Drawings")
		(19 "Cmts.User" user "User.Comments")
		(21 "Eco1.User" user "User.Eco1")
		(23 "Eco2.User" user "User.Eco2")
		(25 "Edge.Cuts" user "Board Geometry/Outline")
		(27 "Margin" user)
		(31 "F.CrtYd" user "Package Geometry/Place Bound Top")
		(29 "B.CrtYd" user "Package Geometry/Place Bound Bottom")
		(35 "F.Fab" user "Ref Des/Assembly Top")
		(33 "B.Fab" user "Ref Des/Assembly Bottom")
	)
	(footprint ""
		(layer "F.Cu")
		(at 414.418018 -255.560068 180)
		(property "Reference" "J16"
			(at 1.474216 81.889092 0)
			(unlocked yes)
			(layer "F.SilkS")
			(effects
				(font
					(size 0.7874 0.5842)
					(thickness 0.1524)
				)
			)
		)
		(property "Value" ""
			(at 0 0 180)
			(layer "F.Fab")
			(effects
				(font
					(size 1.27 1.27)
				)
			)
		)
		(duplicate_pad_numbers_are_jumpers no)
		(pad "1" smd rect
			(at -2.050034 -63.324994 90)
			(size 0.519938 1.4986)
			(layers "F.Cu" "F.Mask" "F.Paste")
			(net "P12V_MEM_CPU0")
		)
		(pad "2" smd rect
			(at -2.050034 -62.47511 90)
			(size 0.519938 1.4986)
			(layers "F.Cu" "F.Mask" "F.Paste")
			(net "Net_2333")
		)
		(pad "3" smd rect
			(at -2.050034 -61.624972 90)
			(size 0.519938 1.4986)
			(layers "F.Cu" "F.Mask" "F.Paste")
			(net "P3V3_AUX")
		)
		(pad "4" smd rect
			(at -2.050034 -60.775088 90)
			(size 0.519938 1.4986)
			(layers "F.Cu" "F.Mask" "F.Paste")
			(net "I3C_SPD_DDRG_CPU0_SCL")
		)
		(pad "5" smd rect
			(at -2.050034 -59.92495 90)
			(size 0.519938 1.4986)
			(layers "F.Cu" "F.Mask" "F.Paste")
			(net "I3C_SPD_DDRG_CPU0_SDA")
		)
		(pad "6" smd rect
			(at -2.050034 -59.075066 90)
			(size 0.519938 1.4986)
			(layers "F.Cu" "F.Mask" "F.Paste")
			(net "GND")
		)
		(pad "7" smd rect
			(at -2.050034 -58.224928 90)
			(size 0.519938 1.4986)
			(layers "F.Cu" "F.Mask" "F.Paste")
			(net "M_G_CPU0_SA_DQ<0>")
		)
		(pad "8" smd rect
			(at -2.050034 -57.375044 90)
			(size 0.519938 1.4986)
			(layers "F.Cu" "F.Mask" "F.Paste")
			(net "GND")
		)
		(pad "9" smd rect
			(at -2.050034 -56.524906 90)
			(size 0.519938 1.4986)
			(layers "F.Cu" "F.Mask" "F.Paste")
			(net "M_G_CPU0_SA_DQ<1>")
		)
		(pad "10" smd rect
			(at -2.050034 -55.675022 90)
			(size 0.519938 1.4986)
			(layers "F.Cu" "F.Mask" "F.Paste")
			(net "GND")
		)
		(pad "11" smd rect
			(at -2.050034 -54.824884 90)
			(size 0.519938 1.4986)
			(layers "F.Cu" "F.Mask" "F.Paste")
			(net "M_G_CPU0_SA_DQS_DP<0>")
		)
		(pad "12" smd rect
			(at -2.050034 -53.975 90)
			(size 0.519938 1.4986)
			(layers "F.Cu" "F.Mask" "F.Paste")
			(net "M_G_CPU0_SA_DQS_DN<0>")
		)
		(pad "13" smd rect
			(at -2.050034 -53.125116 90)
			(size 0.519938 1.4986)
			(layers "F.Cu" "F.Mask" "F.Paste")
			(net "GND")
		)
		(pad "14" smd rect
			(at -2.050034 -52.274978 90)
			(size 0.519938 1.4986)
			(layers "F.Cu" "F.Mask" "F.Paste")
			(net "M_G_CPU0_SA_DQ<4>")
		)
		(pad "15" smd rect
			(at -2.050034 -51.425094 90)
			(size 0.519938 1.4986)
			(layers "F.Cu" "F.Mask" "F.Paste")
			(net "GND")
		)
		(pad "16" smd rect
			(at -2.050034 -50.574956 90)
			(size 0.519938 1.4986)
			(layers "F.Cu" "F.Mask" "F.Paste")
			(net "M_G_CPU0_SA_DQ<5>")
		)
		(pad "17" smd rect
			(at -2.050034 -49.725072 90)
			(size 0.519938 1.4986)
			(layers "F.Cu" "F.Mask" "F.Paste")
			(net "GND")
		)
		(pad "18" smd rect
			(at -2.050034 -48.874934 90)
			(size 0.519938 1.4986)
			(layers "F.Cu" "F.Mask" "F.Paste")
			(net "M_G_CPU0_SA_DQ<8>")
		)
		(pad "19" smd rect
			(at -2.050034 -48.02505 90)
			(size 0.519938 1.4986)
			(layers "F.Cu" "F.Mask" "F.Paste")
			(net "GND")
		)
		(pad "20" smd rect
			(at -2.050034 -47.174912 90)
			(size 0.519938 1.4986)
			(layers "F.Cu" "F.Mask" "F.Paste")
			(net "M_G_CPU0_SA_DQ<9>")
		)
		(pad "21" smd rect
			(at -2.050034 -46.325028 90)
			(size 0.519938 1.4986)
			(layers "F.Cu" "F.Mask" "F.Paste")
			(net "GND")
		)
		(pad "22" smd rect
			(at -2.050034 -45.47489 90)
			(size 0.519938 1.4986)
			(layers "F.Cu" "F.Mask" "F.Paste")
			(net "M_G_CPU0_SA_DQS_DP<1>")
		)
		(pad "23" smd rect
			(at -2.050034 -44.625006 90)
			(size 0.519938 1.4986)
			(layers "F.Cu" "F.Mask" "F.Paste")
			(net "M_G_CPU0_SA_DQS_DN<1>")
		)
		(pad "24" smd rect
			(at -2.050034 -43.775122 90)
			(size 0.519938 1.4986)
			(layers "F.Cu" "F.Mask" "F.Paste")
			(net "GND")
		)
		(pad "25" smd rect
			(at -2.050034 -42.924984 90)
			(size 0.519938 1.4986)
			(layers "F.Cu" "F.Mask" "F.Paste")
			(net "M_G_CPU0_SA_DQ<12>")
		)
		(pad "26" smd rect
			(at -2.050034 -42.0751 90)
			(size 0.519938 1.4986)
			(layers "F.Cu" "F.Mask" "F.Paste")
			(net "GND")
		)
		(pad "27" smd rect
			(at -2.050034 -41.224962 90)
			(size 0.519938 1.4986)
			(layers "F.Cu" "F.Mask" "F.Paste")
			(net "M_G_CPU0_SA_DQ<13>")
		)
		(pad "28" smd rect
			(at -2.050034 -40.375078 90)
			(size 0.519938 1.4986)
			(layers "F.Cu" "F.Mask" "F.Paste")
			(net "GND")
		)
		(pad "29" smd rect
			(at -2.050034 -39.52494 90)
			(size 0.519938 1.4986)
			(layers "F.Cu" "F.Mask" "F.Paste")
			(net "M_G_CPU0_SA_DQ<16>")
		)
		(pad "30" smd rect
			(at -2.050034 -38.675056 90)
			(size 0.519938 1.4986)
			(layers "F.Cu" "F.Mask" "F.Paste")
			(net "GND")
		)
		(pad "31" smd rect
			(at -2.050034 -37.824918 90)
			(size 0.519938 1.4986)
			(layers "F.Cu" "F.Mask" "F.Paste")
			(net "M_G_CPU0_SA_DQ<17>")
		)
		(pad "32" smd rect
			(at -2.050034 -36.975034 90)
			(size 0.519938 1.4986)
			(layers "F.Cu" "F.Mask" "F.Paste")
			(net "GND")
		)
		(pad "33" smd rect
			(at -2.050034 -36.124896 90)
			(size 0.519938 1.4986)
			(layers "F.Cu" "F.Mask" "F.Paste")
			(net "M_G_CPU0_SA_DQS_DP<2>")
		)
		(pad "34" smd rect
			(at -2.050034 -35.275012 90)
			(size 0.519938 1.4986)
			(layers "F.Cu" "F.Mask" "F.Paste")
			(net "M_G_CPU0_SA_DQS_DN<2>")
		)
		(pad "35" smd rect
			(at -2.050034 -34.425128 90)
			(size 0.519938 1.4986)
			(layers "F.Cu" "F.Mask" "F.Paste")
			(net "GND")
		)
		(pad "36" smd rect
			(at -2.050034 -33.57499 90)
			(size 0.519938 1.4986)
			(layers "F.Cu" "F.Mask" "F.Paste")
			(net "M_G_CPU0_SA_DQ<20>")
		)
		(pad "37" smd rect
			(at -2.050034 -32.725106 90)
			(size 0.519938 1.4986)
			(layers "F.Cu" "F.Mask" "F.Paste")
			(net "GND")
		)
		(pad "38" smd rect
			(at -2.050034 -31.874968 90)
			(size 0.519938 1.4986)
			(layers "F.Cu" "F.Mask" "F.Paste")
			(net "M_G_CPU0_SA_DQ<21>")
		)
		(pad "39" smd rect
			(at -2.050034 -31.025084 90)
			(size 0.519938 1.4986)
			(layers "F.Cu" "F.Mask" "F.Paste")
			(net "GND")
		)
		(pad "40" smd rect
			(at -2.050034 -30.174946 90)
			(size 0.519938 1.4986)
			(layers "F.Cu" "F.Mask" "F.Paste")
			(net "M_G_CPU0_SA_DQ<24>")
		)
		(pad "41" smd rect
			(at -2.050034 -29.325062 90)
			(size 0.519938 1.4986)
			(layers "F.Cu" "F.Mask" "F.Paste")
			(net "GND")
		)
		(pad "42" smd rect
			(at -2.050034 -28.474924 90)
			(size 0.519938 1.4986)
			(layers "F.Cu" "F.Mask" "F.Paste")
			(net "M_G_CPU0_SA_DQ<25>")
		)
		(pad "43" smd rect
			(at -2.050034 -27.62504 90)
			(size 0.519938 1.4986)
			(layers "F.Cu" "F.Mask" "F.Paste")
			(net "GND")
		)
		(pad "44" smd rect
			(at -2.050034 -26.774902 90)
			(size 0.519938 1.4986)
			(layers "F.Cu" "F.Mask" "F.Paste")
			(net "M_G_CPU0_SA_DQS_DP<3>")
		)
		(pad "45" smd rect
			(at -2.050034 -25.925018 90)
			(size 0.519938 1.4986)
			(layers "F.Cu" "F.Mask" "F.Paste")
			(net "M_G_CPU0_SA_DQS_DN<3>")
		)
		(pad "46" smd rect
			(at -2.050034 -25.07488 90)
			(size 0.519938 1.4986)
			(layers "F.Cu" "F.Mask" "F.Paste")
			(net "GND")
		)
	)
)
